FILE_TYPE=LIBRARY_PARTS;
primitive 'SCONN3_212H9103GBR1';
  pin
    '3':
      PIN_NUMBER='(3)';
      BIDIRECTIONAL='TRUE';
      INPUT_LOAD='(-0.01,0.01)';
      OUTPUT_LOAD='(1.0,-1.0)';
    '2':
      PIN_NUMBER='(2)';
      BIDIRECTIONAL='TRUE';
      INPUT_LOAD='(-0.01,0.01)';
      OUTPUT_LOAD='(1.0,-1.0)';
    '1':
      PIN_NUMBER='(1)';
      BIDIRECTIONAL='TRUE';
      INPUT_LOAD='(-0.01,0.01)';
      OUTPUT_LOAD='(1.0,-1.0)';
  end_pin;
  body
    PART_NAME='SCONN3_212H9103GBR1';
    BODY_NAME='SCONN3_212H9103GBR1';
    PHYS_DES_PREFIX='J';
    CLASS='IO';
  end_body;
end_primitive;

END.
